(kicad_pcb
	(version 20241229)
	(generator "pcbnew")
	(generator_version "9.0")
	(general
		(thickness 1.63)
		(legacy_teardrops no)
	)
	(paper "A4")
	(title_block
		(title "CM4 Baseboard")
		(date "2026-01-05")
		(rev "1.1.1")
		(company "Antmicro Ltd")
		(comment 1 "www.antmicro.com")
		(comment 9 "footprints 465-469 of 506")
	)
	(layers
		(0 "F.Cu" signal)
		(4 "In1.Cu" power)
		(6 "In2.Cu" power)
		(8 "In3.Cu" signal)
		(10 "In4.Cu" signal)
		(2 "B.Cu" signal)
		(9 "F.Adhes" user "F.Adhesive")
		(11 "B.Adhes" user "B.Adhesive")
		(13 "F.Paste" user)
		(15 "B.Paste" user)
		(5 "F.SilkS" user "F.Silkscreen")
		(7 "B.SilkS" user "B.Silkscreen")
		(1 "F.Mask" user)
		(3 "B.Mask" user)
		(17 "Dwgs.User" user "User.Drawings")
		(19 "Cmts.User" user "User.Comments")
		(21 "Eco1.User" user "User.Eco1")
		(23 "Eco2.User" user "User.Eco2")
		(25 "Edge.Cuts" user)
		(27 "Margin" user)
		(31 "F.CrtYd" user "F.Courtyard")
		(29 "B.CrtYd" user "B.Courtyard")
		(35 "F.Fab" user)
		(33 "B.Fab" user)
	)
	(footprint "antmicro-footprints:R_0402_1005Metric"
		(layer "B.Cu")
		(at 82.542962 135.5415 90)
		(descr "Resistor SMD 0402")
		(tags "resistor SMD 0402")
		(property "Reference" "R923"
			(at -3.485 0.445 90)
			(layer "B.SilkS")
			(effects
				(font
					(size 0.7 0.7)
					(thickness 0.15)
				)
				(justify right bottom mirror)
			)
		)
		(property "Value" "R_2k2_0402"
			(at -1.011843 -1.772047 90)
			(layer "B.Fab")
			(effects
				(font
					(size 0.7 0.7)
					(thickness 0.15)
				)
				(justify right bottom mirror)
			)
		)
		(property "Datasheet" "https://www.bourns.com/docs/product-datasheets/cr.pdf"
			(at 0 0 90)
			(layer "B.Fab")
			(hide yes)
			(effects
				(font
					(size 1.27 1.27)
					(thickness 0.15)
				)
			)
		)
		(property "MPN" "CR0402-FX-2201GLF"
			(at 0 0 90)
			(unlocked yes)
			(layer "B.Fab")
			(hide yes)
			(effects
				(font
					(size 1 1)
					(thickness 0.15)
				)
				(justify mirror)
			)
		)
		(property "Manufacturer" "Bourns"
			(at 0 0 90)
			(unlocked yes)
			(layer "B.Fab")
			(hide yes)
			(effects
				(font
					(size 1 1)
					(thickness 0.15)
				)
				(justify mirror)
			)
		)
		(property "License" "Apache-2.0"
			(at 0 0 90)
			(unlocked yes)
			(layer "B.Fab")
			(hide yes)
			(effects
				(font
					(size 1 1)
					(thickness 0.15)
				)
				(justify mirror)
			)
		)
		(property "Author" "Antmicro"
			(at 0 0 90)
			(unlocked yes)
			(layer "B.Fab")
			(hide yes)
			(effects
				(font
					(size 1 1)
					(thickness 0.15)
				)
				(justify mirror)
			)
		)
		(property "Val" "2k2"
			(at 0 0 90)
			(unlocked yes)
			(layer "B.Fab")
			(hide yes)
			(effects
				(font
					(size 1 1)
					(thickness 0.15)
				)
				(justify mirror)
			)
		)
		(property "Tolerance" "1%"
			(at 0 0 90)
			(unlocked yes)
			(layer "B.Fab")
			(hide yes)
			(effects
				(font
					(size 1 1)
					(thickness 0.15)
				)
				(justify mirror)
			)
		)
		(sheetname "/USB/")
		(sheetfile "usb.kicad_sch")
		(attr smd)
		(fp_rect
			(start -0.925 0.47)
			(end 0.925 -0.47)
			(stroke
				(width 0.05)
				(type default)
			)
			(fill no)
			(layer "B.CrtYd")
		)
		(fp_rect
			(start -0.5 0.25)
			(end 0.5 -0.25)
			(stroke
				(width 0.15)
				(type solid)
			)
			(fill no)
			(layer "B.Fab")
		)
		(fp_text user "${REFERENCE}"
			(at -0.95 -3.168 270)
			(layer "B.Fab")
			(effects
				(font
					(size 0.7 0.7)
					(thickness 0.15)
				)
				(justify left bottom mirror)
			)
		)
		(fp_text user "License: Apache-2.0"
			(at -0.95 -5.169 270)
			(layer "B.Fab")
			(effects
				(font
					(size 0.7 0.7)
					(thickness 0.15)
				)
				(justify left bottom mirror)
			)
		)
		(fp_text user "Author: Antmicro"
			(at -0.95 -4.169 270)
			(layer "B.Fab")
			(effects
				(font
					(size 0.7 0.7)
					(thickness 0.15)
				)
				(justify left bottom mirror)
			)
		)
		(pad "1" smd roundrect
			(at -0.48 0 90)
			(size 0.59 0.64)
			(layers "B.Cu" "B.Mask" "B.Paste")
			(roundrect_rratio 0.25)
			(net 379 "Net-(U905-~{RESET})")
			(pintype "passive")
		)
		(pad "2" smd roundrect
			(at 0.48 0 90)
			(size 0.59 0.64)
			(layers "B.Cu" "B.Mask" "B.Paste")
			(roundrect_rratio 0.25)
			(net 27 "/USB/USB_3V3")
			(pintype "passive")
		)
	)
	(footprint "antmicro-footprints:R_0402_1005Metric"
		(layer "B.Cu")
		(at 86.48 118.4)
		(descr "Resistor SMD 0402")
		(tags "resistor SMD 0402")
		(property "Reference" "R934"
			(at 0 -1.1 0)
			(layer "B.SilkS")
			(effects
				(font
					(size 0.7 0.7)
					(thickness 0.15)
				)
				(justify right bottom mirror)
			)
		)
		(property "Value" "R_10k_0402"
			(at -1.011843 -1.772047 0)
			(layer "B.Fab")
			(effects
				(font
					(size 0.7 0.7)
					(thickness 0.15)
				)
				(justify right bottom mirror)
			)
		)
		(property "Datasheet" "https://www.bourns.com/docs/product-datasheets/cr.pdf"
			(at 0 0 0)
			(layer "B.Fab")
			(hide yes)
			(effects
				(font
					(size 1.27 1.27)
					(thickness 0.15)
				)
			)
		)
		(property "Manufacturer" "Bourns"
			(at 0 0 0)
			(unlocked yes)
			(layer "B.Fab")
			(hide yes)
			(effects
				(font
					(size 1 1)
					(thickness 0.15)
				)
				(justify mirror)
			)
		)
		(property "MPN" "CR0402-FX-1002GLF"
			(at 0 0 0)
			(unlocked yes)
			(layer "B.Fab")
			(hide yes)
			(effects
				(font
					(size 1 1)
					(thickness 0.15)
				)
				(justify mirror)
			)
		)
		(property "Val" "10k"
			(at 0 0 0)
			(unlocked yes)
			(layer "B.Fab")
			(hide yes)
			(effects
				(font
					(size 1 1)
					(thickness 0.15)
				)
				(justify mirror)
			)
		)
		(property "License" "Apache-2.0"
			(at 0 0 0)
			(unlocked yes)
			(layer "B.Fab")
			(hide yes)
			(effects
				(font
					(size 1 1)
					(thickness 0.15)
				)
				(justify mirror)
			)
		)
		(property "Author" "Antmicro"
			(at 0 0 0)
			(unlocked yes)
			(layer "B.Fab")
			(hide yes)
			(effects
				(font
					(size 1 1)
					(thickness 0.15)
				)
				(justify mirror)
			)
		)
		(property "Tolerance" "1%"
			(at 0 0 0)
			(unlocked yes)
			(layer "B.Fab")
			(hide yes)
			(effects
				(font
					(size 1 1)
					(thickness 0.15)
				)
				(justify mirror)
			)
		)
		(sheetname "/USB/")
		(sheetfile "usb.kicad_sch")
		(attr smd)
		(fp_rect
			(start -0.925 0.47)
			(end 0.925 -0.47)
			(stroke
				(width 0.05)
				(type default)
			)
			(fill no)
			(layer "B.CrtYd")
		)
		(fp_rect
			(start -0.5 0.25)
			(end 0.5 -0.25)
			(stroke
				(width 0.15)
				(type solid)
			)
			(fill no)
			(layer "B.Fab")
		)
		(fp_text user "License: Apache-2.0"
			(at -0.95 -5.169 180)
			(layer "B.Fab")
			(effects
				(font
					(size 0.7 0.7)
					(thickness 0.15)
				)
				(justify left bottom mirror)
			)
		)
		(fp_text user "${REFERENCE}"
			(at -0.95 -3.168 180)
			(layer "B.Fab")
			(effects
				(font
					(size 0.7 0.7)
					(thickness 0.15)
				)
				(justify left bottom mirror)
			)
		)
		(fp_text user "Author: Antmicro"
			(at -0.95 -4.169 180)
			(layer "B.Fab")
			(effects
				(font
					(size 0.7 0.7)
					(thickness 0.15)
				)
				(justify left bottom mirror)
			)
		)
		(pad "1" smd roundrect
			(at -0.48 0)
			(size 0.59 0.64)
			(layers "B.Cu" "B.Mask" "B.Paste")
			(roundrect_rratio 0.25)
			(net 499 "Net-(Q906-G)")
			(pintype "passive")
		)
		(pad "2" smd roundrect
			(at 0.48 0)
			(size 0.59 0.64)
			(layers "B.Cu" "B.Mask" "B.Paste")
			(roundrect_rratio 0.25)
			(net 3 "GND")
			(pintype "passive")
		)
	)
	(footprint "antmicro-footprints:TSOT23-6"
		(layer "B.Cu")
		(at 87.317962 125.6165 90)
		(property "Reference" "U903"
			(at -4.74 -0.85 90)
			(layer "B.SilkS")
			(effects
				(font
					(size 0.7 0.7)
					(thickness 0.15)
				)
				(justify right bottom mirror)
			)
		)
		(property "Value" "AP62301_TSOT"
			(at 0 -2.6 90)
			(layer "B.Fab")
			(effects
				(font
					(size 0.7 0.7)
					(thickness 0.15)
				)
				(justify right bottom mirror)
			)
		)
		(property "Datasheet" "https://www.diodes.com/assets/Datasheets/AP62300_AP62301_AP62300T.pdf"
			(at 0 0 90)
			(layer "B.Fab")
			(hide yes)
			(effects
				(font
					(size 1.27 1.27)
					(thickness 0.15)
				)
			)
		)
		(property "MPN" "AP62301WU-7"
			(at 0 0 90)
			(unlocked yes)
			(layer "B.Fab")
			(hide yes)
			(effects
				(font
					(size 1 1)
					(thickness 0.15)
				)
				(justify mirror)
			)
		)
		(property "Manufacturer" "Diodes Incorporated"
			(at 0 0 90)
			(unlocked yes)
			(layer "B.Fab")
			(hide yes)
			(effects
				(font
					(size 1 1)
					(thickness 0.15)
				)
				(justify mirror)
			)
		)
		(property "Author" "Antmicro"
			(at 0 0 90)
			(unlocked yes)
			(layer "B.Fab")
			(hide yes)
			(effects
				(font
					(size 1 1)
					(thickness 0.15)
				)
				(justify mirror)
			)
		)
		(property "License" "Apache-2.0"
			(at 0 0 90)
			(unlocked yes)
			(layer "B.Fab")
			(hide yes)
			(effects
				(font
					(size 1 1)
					(thickness 0.15)
				)
				(justify mirror)
			)
		)
		(sheetname "/USB/")
		(sheetfile "usb.kicad_sch")
		(attr smd)
		(fp_line
			(start 1 -1.55)
			(end -1 -1.55)
			(stroke
				(width 0.15)
				(type solid)
			)
			(layer "B.SilkS")
		)
		(fp_line
			(start 1 -1.55)
			(end 1 -1.4)
			(stroke
				(width 0.15)
				(type solid)
			)
			(layer "B.SilkS")
		)
		(fp_line
			(start -1 -1.55)
			(end -1 -1.4)
			(stroke
				(width 0.15)
				(type solid)
			)
			(layer "B.SilkS")
		)
		(fp_line
			(start 1 1.497)
			(end 1 1.375)
			(stroke
				(width 0.15)
				(type solid)
			)
			(layer "B.SilkS")
		)
		(fp_line
			(start 1 1.497)
			(end -1 1.5)
			(stroke
				(width 0.15)
				(type solid)
			)
			(layer "B.SilkS")
		)
		(fp_line
			(start -1 1.5)
			(end -1 1.375)
			(stroke
				(width 0.15)
				(type solid)
			)
			(layer "B.SilkS")
		)
		(fp_circle
			(center -1.44 1.5)
			(end -1.39 1.5)
			(stroke
				(width 0.15)
				(type solid)
			)
			(fill yes)
			(layer "B.SilkS")
		)
		(fp_rect
			(start 1.93 1.7)
			(end -1.93 -1.7)
			(stroke
				(width 0.05)
				(type solid)
			)
			(fill no)
			(layer "B.CrtYd")
		)
		(fp_line
			(start -0.45 1.521)
			(end -0.876 1.096)
			(stroke
				(width 0.15)
				(type solid)
			)
			(layer "B.Fab")
		)
		(fp_rect
			(start 0.875 -1.528)
			(end -0.875 1.525)
			(stroke
				(width 0.15)
				(type solid)
			)
			(fill no)
			(layer "B.Fab")
		)
		(fp_text user "License: Apache-2.0"
			(at -1.93 -6.199 270)
			(layer "B.Fab")
			(effects
				(font
					(size 0.7 0.7)
					(thickness 0.15)
				)
				(justify left bottom mirror)
			)
		)
		(fp_text user "${REFERENCE}"
			(at -1.93 -3.8 270)
			(layer "B.Fab")
			(effects
				(font
					(size 0.7 0.7)
					(thickness 0.15)
				)
				(justify left bottom mirror)
			)
		)
		(fp_text user "Author: Antmicro"
			(at -1.93 -5 270)
			(layer "B.Fab")
			(effects
				(font
					(size 0.7 0.7)
					(thickness 0.15)
				)
				(justify left bottom mirror)
			)
		)
		(pad "1" smd rect
			(at -1.301 0.947 180)
			(size 0.7 1.2)
			(layers "B.Cu" "B.Mask" "B.Paste")
			(net 3 "GND")
			(pinfunction "GND")
			(pintype "power_in")
		)
		(pad "2" smd rect
			(at -1.301 -0.004 180)
			(size 0.7 1.2)
			(layers "B.Cu" "B.Mask" "B.Paste")
			(net 111 "/USB/SW_FTDI")
			(pinfunction "SW")
			(pintype "power_out")
		)
		(pad "3" smd rect
			(at -1.301 -0.954 180)
			(size 0.7 1.2)
			(layers "B.Cu" "B.Mask" "B.Paste")
			(net 26 "/USB/USBD_VBUS")
			(pinfunction "VIN")
			(pintype "power_in")
		)
		(pad "4" smd rect
			(at 1.299 -0.954 180)
			(size 0.7 1.2)
			(layers "B.Cu" "B.Mask" "B.Paste")
			(net 344 "/USB/FB_FTDI")
			(pinfunction "FB")
			(pintype "input")
		)
		(pad "5" smd rect
			(at 1.299 -0.004 180)
			(size 0.7 1.2)
			(layers "B.Cu" "B.Mask" "B.Paste")
			(net 343 "/USB/EN_FTDI")
			(pinfunction "EN")
			(pintype "input")
		)
		(pad "6" smd rect
			(at 1.299 0.947 180)
			(size 0.7 1.2)
			(layers "B.Cu" "B.Mask" "B.Paste")
			(net 112 "Net-(U903-BST)")
			(pinfunction "BST")
			(pintype "output")
		)
	)
	(footprint "antmicro-footprints:C_0805_2012Metric"
		(layer "B.Cu")
		(at 89.617962 128.8665 180)
		(descr "Capacitor SMD 0805")
		(tags "capacitor SMD 0805")
		(property "Reference" "C907"
			(at -1.87 -3.67 0)
			(layer "B.SilkS")
			(effects
				(font
					(size 0.7 0.7)
					(thickness 0.15)
				)
				(justify left bottom mirror)
			)
		)
		(property "Value" "C_22u_25V_0805"
			(at -2.055717 -1.963152 0)
			(layer "B.Fab")
			(effects
				(font
					(size 0.7 0.7)
					(thickness 0.15)
				)
				(justify left bottom mirror)
			)
		)
		(property "Datasheet" "https://product.samsungsem.com/mlcc/CL21A226MAYNNN.do"
			(at 0 0 180)
			(layer "B.Fab")
			(hide yes)
			(effects
				(font
					(size 1.27 1.27)
					(thickness 0.15)
				)
			)
		)
		(property "Manufacturer" "Samsung Electro-Mechanics"
			(at 0 0 180)
			(unlocked yes)
			(layer "B.Fab")
			(hide yes)
			(effects
				(font
					(size 1 1)
					(thickness 0.15)
				)
				(justify mirror)
			)
		)
		(property "MPN" "CL21A226MAYNNNE"
			(at 0 0 180)
			(unlocked yes)
			(layer "B.Fab")
			(hide yes)
			(effects
				(font
					(size 1 1)
					(thickness 0.15)
				)
				(justify mirror)
			)
		)
		(property "Val" "22u"
			(at 0 0 180)
			(unlocked yes)
			(layer "B.Fab")
			(hide yes)
			(effects
				(font
					(size 1 1)
					(thickness 0.15)
				)
				(justify mirror)
			)
		)
		(property "License" "Apache-2.0"
			(at 0 0 180)
			(unlocked yes)
			(layer "B.Fab")
			(hide yes)
			(effects
				(font
					(size 1 1)
					(thickness 0.15)
				)
				(justify mirror)
			)
		)
		(property "Author" "Antmicro"
			(at 0 0 180)
			(unlocked yes)
			(layer "B.Fab")
			(hide yes)
			(effects
				(font
					(size 1 1)
					(thickness 0.15)
				)
				(justify mirror)
			)
		)
		(property "Voltage" "25V"
			(at 0 0 180)
			(unlocked yes)
			(layer "B.Fab")
			(hide yes)
			(effects
				(font
					(size 1 1)
					(thickness 0.15)
				)
				(justify mirror)
			)
		)
		(property "Dielectric" "X5R"
			(at 0 0 180)
			(unlocked yes)
			(layer "B.Fab")
			(hide yes)
			(effects
				(font
					(size 1 1)
					(thickness 0.15)
				)
				(justify mirror)
			)
		)
		(property "Public" "False"
			(at 0 0 180)
			(unlocked yes)
			(layer "B.Fab")
			(hide yes)
			(effects
				(font
					(size 1 1)
					(thickness 0.15)
				)
				(justify mirror)
			)
		)
		(sheetname "/USB/")
		(sheetfile "usb.kicad_sch")
		(attr smd)
		(fp_line
			(start -0.3 0.7)
			(end 0.3 0.7)
			(stroke
				(width 0.15)
				(type solid)
			)
			(layer "B.SilkS")
		)
		(fp_line
			(start -0.3 -0.7)
			(end 0.3 -0.7)
			(stroke
				(width 0.15)
				(type solid)
			)
			(layer "B.SilkS")
		)
		(fp_rect
			(start 1.95 0.9)
			(end -1.95 -0.9)
			(stroke
				(width 0.05)
				(type default)
			)
			(fill no)
			(layer "B.CrtYd")
		)
		(fp_rect
			(start -0.95 0.675)
			(end 0.95 -0.675)
			(stroke
				(width 0.15)
				(type solid)
			)
			(fill no)
			(layer "B.Fab")
		)
		(fp_text user "${REFERENCE}"
			(at -1.9 -3.947 0)
			(layer "B.Fab")
			(effects
				(font
					(size 0.7 0.7)
					(thickness 0.15)
				)
				(justify left bottom mirror)
			)
		)
		(fp_text user "Author: Antmicro"
			(at -1.9 -5.947 0)
			(layer "B.Fab")
			(effects
				(font
					(size 0.7 0.7)
					(thickness 0.15)
				)
				(justify left bottom mirror)
			)
		)
		(fp_text user "License: Apache-2.0"
			(at -1.9 -4.947 0)
			(layer "B.Fab")
			(effects
				(font
					(size 0.7 0.7)
					(thickness 0.15)
				)
				(justify left bottom mirror)
			)
		)
		(pad "1" smd roundrect
			(at -1.1 0 180)
			(size 1.2 1.3)
			(layers "B.Cu" "B.Mask" "B.Paste")
			(roundrect_rratio 0.25)
			(net 113 "/USB/OUT_FTDI")
			(pintype "passive")
		)
		(pad "2" smd roundrect
			(at 1.1 0 180)
			(size 1.2 1.3)
			(layers "B.Cu" "B.Mask" "B.Paste")
			(roundrect_rratio 0.25)
			(net 3 "GND")
			(pintype "passive")
		)
	)
	(footprint "antmicro-footprints:FB_0603_1608Metric"
		(layer "B.Cu")
		(at 59.242962 113.8915 180)
		(property "Reference" "FB402"
			(at -1.725 0.715 0)
			(layer "B.SilkS")
			(effects
				(font
					(size 0.7 0.7)
					(thickness 0.15)
				)
				(justify left bottom mirror)
			)
		)
		(property "Value" "FB_220Z_2.2A_TDK-MPZ_0603"
			(at 0 -1.5 0)
			(layer "B.Fab")
			(effects
				(font
					(size 0.7 0.7)
					(thickness 0.15)
				)
				(justify left bottom mirror)
			)
		)
		(property "Datasheet" "https://product.tdk.com/info/en/catalog/datasheets/beads_commercial_power_mpz1608_en.pdf"
			(at 0 0 180)
			(layer "B.Fab")
			(hide yes)
			(effects
				(font
					(size 1.27 1.27)
					(thickness 0.15)
				)
			)
		)
		(property "MPN" "MPZ1608S221ATA00"
			(at 0 0 180)
			(unlocked yes)
			(layer "B.Fab")
			(hide yes)
			(effects
				(font
					(size 1 1)
					(thickness 0.15)
				)
				(justify mirror)
			)
		)
		(property "Manufacturer" "TDK"
			(at 0 0 180)
			(unlocked yes)
			(layer "B.Fab")
			(hide yes)
			(effects
				(font
					(size 1 1)
					(thickness 0.15)
				)
				(justify mirror)
			)
		)
		(property "Author" "Antmicro"
			(at 0 0 180)
			(unlocked yes)
			(layer "B.Fab")
			(hide yes)
			(effects
				(font
					(size 1 1)
					(thickness 0.15)
				)
				(justify mirror)
			)
		)
		(property "License" "Apache-2.0"
			(at 0 0 180)
			(unlocked yes)
			(layer "B.Fab")
			(hide yes)
			(effects
				(font
					(size 1 1)
					(thickness 0.15)
				)
				(justify mirror)
			)
		)
		(property "Val" "220Z/2.2A"
			(at 0 0 180)
			(unlocked yes)
			(layer "B.Fab")
			(hide yes)
			(effects
				(font
					(size 1 1)
					(thickness 0.15)
				)
				(justify mirror)
			)
		)
		(property "Current" ""
			(at 0 0 180)
			(unlocked yes)
			(layer "B.Fab")
			(hide yes)
			(effects
				(font
					(size 1 1)
					(thickness 0.15)
				)
				(justify mirror)
			)
		)
		(sheetname "/Ethernet/")
		(sheetfile "ethernet.kicad_sch")
		(attr smd)
		(fp_line
			(start -0.15 0.4)
			(end 0.15 0.4)
			(stroke
				(width 0.15)
				(type solid)
			)
			(layer "B.SilkS")
		)
		(fp_line
			(start -0.15 -0.4)
			(end 0.15 -0.4)
			(stroke
				(width 0.15)
				(type solid)
			)
			(layer "B.SilkS")
		)
		(fp_rect
			(start -1.25 0.65)
			(end 1.25 -0.65)
			(stroke
				(width 0.05)
				(type solid)
			)
			(fill no)
			(layer "B.CrtYd")
		)
		(fp_line
			(start 0.8 0.408)
			(end 0.8 -0.406)
			(stroke
				(width 0.15)
				(type solid)
			)
			(layer "B.Fab")
		)
		(fp_line
			(start 0.8 0.408)
			(end -0.803 0.408)
			(stroke
				(width 0.15)
				(type solid)
			)
			(layer "B.Fab")
		)
		(fp_line
			(start 0.8 -0.406)
			(end -0.803 -0.406)
			(stroke
				(width 0.15)
				(type solid)
			)
			(layer "B.Fab")
		)
		(fp_line
			(start -0.803 -0.406)
			(end -0.803 0.408)
			(stroke
				(width 0.15)
				(type solid)
			)
			(layer "B.Fab")
		)
		(fp_text user "License: Apache-2.0"
			(at -1.653 -5.9 0)
			(layer "B.Fab")
			(effects
				(font
					(size 0.7 0.7)
					(thickness 0.15)
				)
				(justify left bottom mirror)
			)
		)
		(fp_text user "Author: Antmicro"
			(at -1.653 -3.162 0)
			(layer "B.Fab")
			(effects
				(font
					(size 0.7 0.7)
					(thickness 0.15)
				)
				(justify left bottom mirror)
			)
		)
		(fp_text user "${REFERENCE}"
			(at -1.653 -4.6 0)
			(layer "B.Fab")
			(effects
				(font
					(size 0.7 0.7)
					(thickness 0.15)
				)
				(justify left bottom mirror)
			)
		)
		(pad "1" smd roundrect
			(at -0.7 0 180)
			(size 0.8 1)
			(layers "B.Cu" "B.Mask" "B.Paste")
			(roundrect_rratio 0.2)
			(net 116 "Net-(D401-Pad1)")
			(pintype "passive")
		)
		(pad "2" smd roundrect
			(at 0.7 0 180)
			(size 0.8 1)
			(layers "B.Cu" "B.Mask" "B.Paste")
			(roundrect_rratio 0.2)
			(net 90 "/Ethernet/VSS")
			(pintype "passive")
		)
	)
)
